# S9S_MB_2U (Grand Teton) — schematic netlist excerpt (pin names and nets, part order shuffled) for the footprints in the layout excerpt that follows; sources: Cadence DE-HDL packaged netlist, KiCad conversion of 03242023_DA0F0TMBIJ0_F0T_Motherboard_J_brd_V01_OCP.brd

PR156  Q_RES  0 5% CHIP  pkg 0402LF  page 266 : A = P12V_AUX ; B = PVCCIN_CPU0_VIN_CSNIN
PR2523  Q_RES  1 1% EMPTY  pkg 0402LF  page 304 : A = P12V_HSC_SENSE2_P ; B = P12V_HSC_SENSE2_R4_P

(kicad_pcb
	(version 20260206)
	(generator "pcbnew")
	(generator_version "10.0")
	(general
		(thickness 1.6)
		(legacy_teardrops no)
	)
	(paper "A4")
	(title_block
		(title "03242023_DA0F0TMBIJ0_F0T_Motherboard_J_brd_V01_OCP.brd")
		(comment 1 "Grand Teton / footprints 4927-4928 of 6105")
	)
	(layers
		(0 "F.Cu" signal "TOP")
		(4 "In1.Cu" signal "GND")
		(6 "In2.Cu" signal "IN1")
		(8 "In3.Cu" signal "GND1")
		(10 "In4.Cu" signal "IN2")
		(12 "In5.Cu" signal "GND2")
		(14 "In6.Cu" signal "IN3")
		(16 "In7.Cu" signal "GND3")
		(18 "In8.Cu" signal "VCC")
		(20 "In9.Cu" signal "VCC1")
		(22 "In10.Cu" signal "GND4")
		(24 "In11.Cu" signal "IN4")
		(26 "In12.Cu" signal "GND5")
		(28 "In13.Cu" signal "IN5")
		(30 "In14.Cu" signal "GND6")
		(32 "In15.Cu" signal "IN6")
		(34 "In16.Cu" signal "GND7")
		(2 "B.Cu" signal "BOTTOM")
		(9 "F.Adhes" user "F.Adhesive")
		(11 "B.Adhes" user "B.Adhesive")
		(13 "F.Paste" user "Package Geometry/Pastemask Top")
		(15 "B.Paste" user "Package Geometry/Pastemask Bottom")
		(5 "F.SilkS" user "Ref Des/Silkscreen Top")
		(7 "B.SilkS" user "Ref Des/Silkscreen Bottom")
		(1 "F.Mask" user "Board Geometry/Soldermask Top")
		(3 "B.Mask" user "Board Geometry/Soldermask Bottom")
		(17 "Dwgs.User" user "User.Drawings")
		(19 "Cmts.User" user "User.Comments")
		(21 "Eco1.User" user "User.Eco1")
		(23 "Eco2.User" user "User.Eco2")
		(25 "Edge.Cuts" user "Board Geometry/Outline")
		(27 "Margin" user)
		(31 "F.CrtYd" user "Package Geometry/Place Bound Top")
		(29 "B.CrtYd" user "Package Geometry/Place Bound Bottom")
		(35 "F.Fab" user "Ref Des/Assembly Top")
		(33 "B.Fab" user "Ref Des/Assembly Bottom")
	)
	(footprint ""
		(layer "B.Cu")
		(at 293.544498 -400.999452 -90)
		(property "Reference" "PR2523"
			(at 0 0 90)
			(layer "B.SilkS")
			(hide yes)
			(effects
				(font
					(size 1.27 1.27)
				)
				(justify mirror)
			)
		)
		(property "Value" ""
			(at 0 0 90)
			(layer "B.Fab")
			(effects
				(font
					(size 1.27 1.27)
				)
				(justify mirror)
			)
		)
		(duplicate_pad_numbers_are_jumpers no)
		(fp_line
			(start -0.7874 0.4064)
			(end 0.7874 0.4064)
			(stroke
				(width 0.1524)
				(type default)
			)
			(layer "B.SilkS")
		)
		(fp_line
			(start 0.7874 0.4064)
			(end 0.7874 -0.4064)
			(stroke
				(width 0.1524)
				(type default)
			)
			(layer "B.SilkS")
		)
		(fp_line
			(start -0.7874 -0.4064)
			(end -0.7874 0.4064)
			(stroke
				(width 0.1524)
				(type default)
			)
			(layer "B.SilkS")
		)
		(fp_line
			(start 0.7874 -0.4064)
			(end -0.7874 -0.4064)
			(stroke
				(width 0.1524)
				(type default)
			)
			(layer "B.SilkS")
		)
		(fp_line
			(start -0.67945 0.3048)
			(end -0.120396 0.3048)
			(stroke
				(width 0.1)
				(type default)
			)
			(layer "B.Fab")
		)
		(fp_line
			(start -0.120396 0.3048)
			(end -0.120396 0.2794)
			(stroke
				(width 0.1)
				(type default)
			)
			(layer "B.Fab")
		)
		(fp_line
			(start 0.12065 0.3048)
			(end 0.67945 0.3048)
			(stroke
				(width 0.1)
				(type default)
			)
			(layer "B.Fab")
		)
		(fp_line
			(start 0.67945 0.3048)
			(end 0.67945 -0.305054)
			(stroke
				(width 0.1)
				(type default)
			)
			(layer "B.Fab")
		)
		(fp_line
			(start -0.120396 0.2794)
			(end 0.12065 0.2794)
			(stroke
				(width 0.1)
				(type default)
			)
			(layer "B.Fab")
		)
		(fp_line
			(start 0.12065 0.2794)
			(end 0.12065 0.3048)
			(stroke
				(width 0.1)
				(type default)
			)
			(layer "B.Fab")
		)
		(fp_line
			(start -0.12065 -0.2794)
			(end -0.12065 -0.3048)
			(stroke
				(width 0.1)
				(type default)
			)
			(layer "B.Fab")
		)
		(fp_line
			(start 0.12065 -0.2794)
			(end -0.12065 -0.2794)
			(stroke
				(width 0.1)
				(type default)
			)
			(layer "B.Fab")
		)
		(fp_line
			(start -0.67945 -0.3048)
			(end -0.67945 0.3048)
			(stroke
				(width 0.1)
				(type default)
			)
			(layer "B.Fab")
		)
		(fp_line
			(start -0.12065 -0.3048)
			(end -0.67945 -0.3048)
			(stroke
				(width 0.1)
				(type default)
			)
			(layer "B.Fab")
		)
		(fp_line
			(start 0.12065 -0.305054)
			(end 0.12065 -0.2794)
			(stroke
				(width 0.1)
				(type default)
			)
			(layer "B.Fab")
		)
		(fp_line
			(start 0.67945 -0.305054)
			(end 0.12065 -0.305054)
			(stroke
				(width 0.1)
				(type default)
			)
			(layer "B.Fab")
		)
		(pad "1" smd circle
			(at 0.40005 0 90)
			(size 0 0)
			(layers "B.Cu" "B.Mask" "B.Paste")
			(net "P12V_HSC_SENSE2_P")
		)
		(pad "2" smd circle
			(at -0.40005 0 90)
			(size 0 0)
			(layers "B.Cu" "B.Mask" "B.Paste")
			(net "P12V_HSC_SENSE2_R4_P")
		)
	)
	(footprint ""
		(layer "B.Cu")
		(at 361.691174 -361.759246)
		(property "Reference" "PR156"
			(at 0 0 0)
			(layer "B.SilkS")
			(hide yes)
			(effects
				(font
					(size 1.27 1.27)
				)
				(justify mirror)
			)
		)
		(property "Value" ""
			(at 0 0 0)
			(layer "B.Fab")
			(effects
				(font
					(size 1.27 1.27)
				)
				(justify mirror)
			)
		)
		(duplicate_pad_numbers_are_jumpers no)
		(fp_line
			(start -0.7874 -0.4064)
			(end -0.7874 0.4064)
			(stroke
				(width 0.1524)
				(type default)
			)
			(layer "B.SilkS")
		)
		(fp_line
			(start -0.7874 0.4064)
			(end 0.7874 0.4064)
			(stroke
				(width 0.1524)
				(type default)
			)
			(layer "B.SilkS")
		)
		(fp_line
			(start 0.7874 -0.4064)
			(end -0.7874 -0.4064)
			(stroke
				(width 0.1524)
				(type default)
			)
			(layer "B.SilkS")
		)
		(fp_line
			(start 0.7874 0.4064)
			(end 0.7874 -0.4064)
			(stroke
				(width 0.1524)
				(type default)
			)
			(layer "B.SilkS")
		)
		(fp_line
			(start -0.67945 -0.3048)
			(end -0.67945 0.3048)
			(stroke
				(width 0.1)
				(type default)
			)
			(layer "B.Fab")
		)
		(fp_line
			(start -0.67945 0.3048)
			(end -0.120396 0.3048)
			(stroke
				(width 0.1)
				(type default)
			)
			(layer "B.Fab")
		)
		(fp_line
			(start -0.12065 -0.3048)
			(end -0.67945 -0.3048)
			(stroke
				(width 0.1)
				(type default)
			)
			(layer "B.Fab")
		)
		(fp_line
			(start -0.12065 -0.2794)
			(end -0.12065 -0.3048)
			(stroke
				(width 0.1)
				(type default)
			)
			(layer "B.Fab")
		)
		(fp_line
			(start -0.120396 0.2794)
			(end 0.12065 0.2794)
			(stroke
				(width 0.1)
				(type default)
			)
			(layer "B.Fab")
		)
		(fp_line
			(start -0.120396 0.3048)
			(end -0.120396 0.2794)
			(stroke
				(width 0.1)
				(type default)
			)
			(layer "B.Fab")
		)
		(fp_line
			(start 0.12065 -0.305054)
			(end 0.12065 -0.2794)
			(stroke
				(width 0.1)
				(type default)
			)
			(layer "B.Fab")
		)
		(fp_line
			(start 0.12065 -0.2794)
			(end -0.12065 -0.2794)
			(stroke
				(width 0.1)
				(type default)
			)
			(layer "B.Fab")
		)
		(fp_line
			(start 0.12065 0.2794)
			(end 0.12065 0.3048)
			(stroke
				(width 0.1)
				(type default)
			)
			(layer "B.Fab")
		)
		(fp_line
			(start 0.12065 0.3048)
			(end 0.67945 0.3048)
			(stroke
				(width 0.1)
				(type default)
			)
			(layer "B.Fab")
		)
		(fp_line
			(start 0.67945 -0.305054)
			(end 0.12065 -0.305054)
			(stroke
				(width 0.1)
				(type default)
			)
			(layer "B.Fab")
		)
		(fp_line
			(start 0.67945 0.3048)
			(end 0.67945 -0.305054)
			(stroke
				(width 0.1)
				(type default)
			)
			(layer "B.Fab")
		)
		(pad "1" smd circle
			(at 0.40005 0 180)
			(size 0 0)
			(layers "B.Cu" "B.Mask" "B.Paste")
			(net "P12V_AUX")
		)
		(pad "2" smd circle
			(at -0.40005 0 180)
			(size 0 0)
			(layers "B.Cu" "B.Mask" "B.Paste")
			(net "PVCCIN_CPU0_VIN_CSNIN")
		)
	)
)
